(kicad_pcb
	(version 20260206)
	(generator "pcbnew")
	(generator_version "10.0")
	(general
		(thickness 1.6)
		(legacy_teardrops no)
	)
	(paper "A4")
	(title_block
		(title "v1-chassis-manager — T6M_CM_d_v01_1031_1645.brd")
		(comment 1 "Open CloudServer (Microsoft) / footprints 1121-1131 of 2512")
	)
	(layers
		(0 "F.Cu" signal "TOP")
		(4 "In1.Cu" signal "GND1")
		(6 "In2.Cu" signal "IN1")
		(8 "In3.Cu" signal "VCC1")
		(10 "In4.Cu" signal "VCC2")
		(12 "In5.Cu" signal "GND2")
		(14 "In6.Cu" signal "IN2")
		(16 "In7.Cu" signal "IN3")
		(18 "In8.Cu" signal "GND3")
		(2 "B.Cu" signal "BOTTOM")
		(9 "F.Adhes" user "F.Adhesive")
		(11 "B.Adhes" user "B.Adhesive")
		(13 "F.Paste" user "Package Geometry/Pastemask Top")
		(15 "B.Paste" user "Package Geometry/Pastemask Bottom")
		(5 "F.SilkS" user "Ref Des/Silkscreen Top")
		(7 "B.SilkS" user "Ref Des/Silkscreen Bottom")
		(1 "F.Mask" user "Board Geometry/Soldermask Top")
		(3 "B.Mask" user "Board Geometry/Soldermask Bottom")
		(17 "Dwgs.User" user "User.Drawings")
		(19 "Cmts.User" user "User.Comments")
		(21 "Eco1.User" user "User.Eco1")
		(23 "Eco2.User" user "User.Eco2")
		(25 "Edge.Cuts" user "Board Geometry/Outline")
		(27 "Margin" user)
		(31 "F.CrtYd" user "Package Geometry/Place Bound Top")
		(29 "B.CrtYd" user "Package Geometry/Place Bound Bottom")
		(35 "F.Fab" user "Ref Des/Assembly Top")
		(33 "B.Fab" user "Ref Des/Assembly Bottom")
	)
	(footprint ""
		(layer "F.Cu")
		(at 128.940052 -133.00075 90)
		(property "Reference" "C877"
			(at -3.959352 0.148336 90)
			(unlocked yes)
			(layer "F.SilkS")
			(effects
				(font
					(size 0.7874 0.5842)
					(thickness 0.1524)
				)
				(justify left)
			)
		)
		(property "Value" ""
			(at 0 0 90)
			(layer "F.Fab")
			(effects
				(font
					(size 1.27 1.27)
				)
			)
		)
		(duplicate_pad_numbers_are_jumpers no)
		(fp_line
			(start 0.7874 -0.4064)
			(end 0.7874 0.4064)
			(stroke
				(width 0.1524)
				(type default)
			)
			(layer "F.SilkS")
		)
		(fp_line
			(start -0.7874 -0.4064)
			(end 0.7874 -0.4064)
			(stroke
				(width 0.1524)
				(type default)
			)
			(layer "F.SilkS")
		)
		(fp_line
			(start 0 0.381)
			(end 0 -0.381)
			(stroke
				(width 0.1524)
				(type default)
			)
			(layer "F.SilkS")
		)
		(fp_line
			(start 0.7874 0.4064)
			(end -0.7874 0.4064)
			(stroke
				(width 0.1524)
				(type default)
			)
			(layer "F.SilkS")
		)
		(fp_line
			(start -0.7874 0.4064)
			(end -0.7874 -0.4064)
			(stroke
				(width 0.1524)
				(type default)
			)
			(layer "F.SilkS")
		)
		(fp_poly
			(pts
				(xy -0.5334 0.254) (xy -0.635 0.254) (xy -0.635 0.2286) (xy -0.635 -0.254) (xy -0.5334 -0.254) (xy -0.5334 -0.2794)
				(xy 0.5334 -0.2794) (xy 0.5334 -0.254) (xy 0.635 -0.254) (xy 0.635 0.254) (xy 0.5334 0.254) (xy 0.5334 0.2794)
				(xy -0.508 0.2794) (xy -0.5334 0.2794)
			)
			(stroke
				(width 0)
				(type default)
			)
			(fill no)
			(layer "F.CrtYd")
		)
		(pad "1" smd rect
			(at 0.40005 0 90)
			(size 0.4572 0.508)
			(layers "F.Cu" "F.Mask" "F.Paste")
			(net "P1V0_NODE1")
		)
		(pad "2" smd rect
			(at -0.40005 0 90)
			(size 0.4572 0.508)
			(layers "F.Cu" "F.Mask" "F.Paste")
			(net "GND")
		)
	)
	(footprint ""
		(layer "F.Cu")
		(at 18.28038 -90.893392 -90)
		(property "Reference" ""
			(at 0 0 270)
			(layer "F.SilkS")
			(hide yes)
			(effects
				(font
					(size 1.27 1.27)
				)
			)
		)
		(property "Value" ""
			(at 0 0 270)
			(layer "F.Fab")
			(effects
				(font
					(size 1.27 1.27)
				)
			)
		)
		(duplicate_pad_numbers_are_jumpers no)
		(fp_poly
			(pts
				(arc
					(start 0 -1.4986)
					(mid 0 1.4986)
					(end 0 -1.4986)
				)
			)
			(stroke
				(width 0)
				(type default)
			)
			(fill no)
			(layer "F.CrtYd")
		)
		(pad "1" smd circle
			(at 0 0 270)
			(size 0.9906 0.9906)
			(layers "F.Cu" "F.Mask" "F.Paste")
			(net "Net_30")
		)
		(zone
			(layer "F.Cu")
			(hatch none 0.5)
			(connect_pads
				(clearance 0)
			)
			(min_thickness 0.25)
			(keepout
				(tracks not_allowed)
				(vias allowed)
				(pads allowed)
				(copperpour not_allowed)
				(footprints allowed)
			)
			(placement
				(enabled no)
				(sheetname "")
			)
			(fill
				(thermal_gap 0.5)
				(thermal_bridge_width 0.5)
				(island_removal_mode 0)
			)
			(polygon
				(pts
					(arc
						(start 19.90598 -90.893392)
						(mid 16.65478 -90.893392)
						(end 19.90598 -90.893392)
					)
				)
			)
		)
	)
	(footprint ""
		(layer "F.Cu")
		(at 163.255198 -161.395918 90)
		(property "Reference" "R578"
			(at -8.091678 17.572736 90)
			(unlocked yes)
			(layer "F.SilkS")
			(effects
				(font
					(size 0.7874 0.5842)
					(thickness 0.1524)
				)
				(justify left)
			)
		)
		(property "Value" ""
			(at 0 0 90)
			(layer "F.Fab")
			(effects
				(font
					(size 1.27 1.27)
				)
			)
		)
		(duplicate_pad_numbers_are_jumpers no)
		(fp_line
			(start 0.7874 -0.4064)
			(end 0.7874 0.4064)
			(stroke
				(width 0.1524)
				(type default)
			)
			(layer "F.SilkS")
		)
		(fp_line
			(start -0.7874 -0.4064)
			(end 0.7874 -0.4064)
			(stroke
				(width 0.1524)
				(type default)
			)
			(layer "F.SilkS")
		)
		(fp_line
			(start 0.7874 0.4064)
			(end -0.7874 0.4064)
			(stroke
				(width 0.1524)
				(type default)
			)
			(layer "F.SilkS")
		)
		(fp_line
			(start -0.7874 0.4064)
			(end -0.7874 -0.4064)
			(stroke
				(width 0.1524)
				(type default)
			)
			(layer "F.SilkS")
		)
		(fp_poly
			(pts
				(xy -0.508 0.2794) (xy -0.508 0.2286) (xy -0.635 0.2286) (xy -0.635 -0.254) (xy -0.5334 -0.254)
				(xy -0.5334 -0.2794) (xy 0.5334 -0.2794) (xy 0.5334 -0.254) (xy 0.635 -0.254) (xy 0.635 0.254) (xy 0.5334 0.254)
				(xy 0.5334 0.2794)
			)
			(stroke
				(width 0)
				(type default)
			)
			(fill no)
			(layer "F.CrtYd")
		)
		(pad "1" smd rect
			(at 0.40005 0 90)
			(size 0.4572 0.508)
			(layers "F.Cu" "F.Mask" "F.Paste")
			(net "P3V3_NODE1")
		)
		(pad "2" smd rect
			(at -0.40005 0 90)
			(size 0.4572 0.508)
			(layers "F.Cu" "F.Mask" "F.Paste")
			(net "LAN2_NC_SI_RXD0")
		)
	)
	(footprint ""
		(layer "F.Cu")
		(at 77.117194 -158.464758)
		(property "Reference" "PC25"
			(at -1.590294 -1.119886 0)
			(unlocked yes)
			(layer "F.SilkS")
			(effects
				(font
					(size 0.7874 0.5842)
					(thickness 0.1524)
				)
				(justify left)
			)
		)
		(property "Value" ""
			(at 0 0 0)
			(layer "F.Fab")
			(effects
				(font
					(size 1.27 1.27)
				)
			)
		)
		(duplicate_pad_numbers_are_jumpers no)
		(fp_line
			(start -0.7874 -0.4064)
			(end 0.7874 -0.4064)
			(stroke
				(width 0.1524)
				(type default)
			)
			(layer "F.SilkS")
		)
		(fp_line
			(start -0.7874 0.4064)
			(end -0.7874 -0.4064)
			(stroke
				(width 0.1524)
				(type default)
			)
			(layer "F.SilkS")
		)
		(fp_line
			(start 0 0.381)
			(end 0 -0.381)
			(stroke
				(width 0.1524)
				(type default)
			)
			(layer "F.SilkS")
		)
		(fp_line
			(start 0.7874 -0.4064)
			(end 0.7874 0.4064)
			(stroke
				(width 0.1524)
				(type default)
			)
			(layer "F.SilkS")
		)
		(fp_line
			(start 0.7874 0.4064)
			(end -0.7874 0.4064)
			(stroke
				(width 0.1524)
				(type default)
			)
			(layer "F.SilkS")
		)
		(fp_poly
			(pts
				(xy -0.5334 0.254) (xy -0.635 0.254) (xy -0.635 0.2286) (xy -0.635 -0.254) (xy -0.5334 -0.254) (xy -0.5334 -0.2794)
				(xy 0.5334 -0.2794) (xy 0.5334 -0.254) (xy 0.635 -0.254) (xy 0.635 0.254) (xy 0.5334 0.254) (xy 0.5334 0.2794)
				(xy -0.508 0.2794) (xy -0.5334 0.2794)
			)
			(stroke
				(width 0)
				(type default)
			)
			(fill no)
			(layer "F.CrtYd")
		)
		(pad "1" smd rect
			(at 0.40005 0)
			(size 0.4572 0.508)
			(layers "F.Cu" "F.Mask" "F.Paste")
			(net "P5V_STB_NODE1_EN")
		)
		(pad "2" smd rect
			(at -0.40005 0)
			(size 0.4572 0.508)
			(layers "F.Cu" "F.Mask" "F.Paste")
			(net "GND")
		)
	)
	(footprint ""
		(layer "F.Cu")
		(at 14.059154 -133.218428 90)
		(property "Reference" "PC69"
			(at -0.494792 -2.139696 90)
			(unlocked yes)
			(layer "F.SilkS")
			(effects
				(font
					(size 0.7874 0.5842)
					(thickness 0.1524)
				)
				(justify left)
			)
		)
		(property "Value" ""
			(at 0 0 90)
			(layer "F.Fab")
			(effects
				(font
					(size 1.27 1.27)
				)
			)
		)
		(duplicate_pad_numbers_are_jumpers no)
		(fp_line
			(start 0.7874 -0.4064)
			(end 0.7874 0.4064)
			(stroke
				(width 0.1524)
				(type default)
			)
			(layer "F.SilkS")
		)
		(fp_line
			(start -0.7874 -0.4064)
			(end 0.7874 -0.4064)
			(stroke
				(width 0.1524)
				(type default)
			)
			(layer "F.SilkS")
		)
		(fp_line
			(start 0 0.381)
			(end 0 -0.381)
			(stroke
				(width 0.1524)
				(type default)
			)
			(layer "F.SilkS")
		)
		(fp_line
			(start 0.7874 0.4064)
			(end -0.7874 0.4064)
			(stroke
				(width 0.1524)
				(type default)
			)
			(layer "F.SilkS")
		)
		(fp_line
			(start -0.7874 0.4064)
			(end -0.7874 -0.4064)
			(stroke
				(width 0.1524)
				(type default)
			)
			(layer "F.SilkS")
		)
		(fp_poly
			(pts
				(xy -0.5334 0.254) (xy -0.635 0.254) (xy -0.635 0.2286) (xy -0.635 -0.254) (xy -0.5334 -0.254) (xy -0.5334 -0.2794)
				(xy 0.5334 -0.2794) (xy 0.5334 -0.254) (xy 0.635 -0.254) (xy 0.635 0.254) (xy 0.5334 0.254) (xy 0.5334 0.2794)
				(xy -0.508 0.2794) (xy -0.5334 0.2794)
			)
			(stroke
				(width 0)
				(type default)
			)
			(fill no)
			(layer "F.CrtYd")
		)
		(pad "1" smd rect
			(at 0.40005 0 90)
			(size 0.4572 0.508)
			(layers "F.Cu" "F.Mask" "F.Paste")
			(net "P1V05_NODE1_VSNS")
		)
		(pad "2" smd rect
			(at -0.40005 0 90)
			(size 0.4572 0.508)
			(layers "F.Cu" "F.Mask" "F.Paste")
			(net "P1V05_NODE1_COMP")
		)
	)
	(footprint ""
		(layer "F.Cu")
		(at 61.96076 -185.205624 90)
		(property "Reference" "C700"
			(at 4.006088 -0.601218 90)
			(unlocked yes)
			(layer "F.SilkS")
			(effects
				(font
					(size 0.7874 0.5842)
					(thickness 0.1524)
				)
				(justify left)
			)
		)
		(property "Value" ""
			(at 0 0 90)
			(layer "F.Fab")
			(effects
				(font
					(size 1.27 1.27)
				)
			)
		)
		(duplicate_pad_numbers_are_jumpers no)
		(fp_line
			(start 0.7874 -0.4064)
			(end 0.7874 0.4064)
			(stroke
				(width 0.1524)
				(type default)
			)
			(layer "F.SilkS")
		)
		(fp_line
			(start -0.7874 -0.4064)
			(end 0.7874 -0.4064)
			(stroke
				(width 0.1524)
				(type default)
			)
			(layer "F.SilkS")
		)
		(fp_line
			(start 0 0.381)
			(end 0 -0.381)
			(stroke
				(width 0.1524)
				(type default)
			)
			(layer "F.SilkS")
		)
		(fp_line
			(start 0.7874 0.4064)
			(end -0.7874 0.4064)
			(stroke
				(width 0.1524)
				(type default)
			)
			(layer "F.SilkS")
		)
		(fp_line
			(start -0.7874 0.4064)
			(end -0.7874 -0.4064)
			(stroke
				(width 0.1524)
				(type default)
			)
			(layer "F.SilkS")
		)
		(fp_poly
			(pts
				(xy -0.5334 0.254) (xy -0.635 0.254) (xy -0.635 0.2286) (xy -0.635 -0.254) (xy -0.5334 -0.254) (xy -0.5334 -0.2794)
				(xy 0.5334 -0.2794) (xy 0.5334 -0.254) (xy 0.635 -0.254) (xy 0.635 0.254) (xy 0.5334 0.254) (xy 0.5334 0.2794)
				(xy -0.508 0.2794) (xy -0.5334 0.2794)
			)
			(stroke
				(width 0)
				(type default)
			)
			(fill no)
			(layer "F.CrtYd")
		)
		(pad "1" smd rect
			(at 0.40005 0 90)
			(size 0.4572 0.508)
			(layers "F.Cu" "F.Mask" "F.Paste")
			(net "UART_T2_NODE2_RXD")
		)
		(pad "2" smd rect
			(at -0.40005 0 90)
			(size 0.4572 0.508)
			(layers "F.Cu" "F.Mask" "F.Paste")
			(net "GND")
		)
	)
	(footprint ""
		(layer "F.Cu")
		(at 8.34009 -6.709156 180)
		(property "Reference" "R214"
			(at 6.44398 0.688086 0)
			(unlocked yes)
			(layer "F.SilkS")
			(effects
				(font
					(size 0.7874 0.5842)
					(thickness 0.1524)
				)
				(justify left)
			)
		)
		(property "Value" ""
			(at 0 0 180)
			(layer "F.Fab")
			(effects
				(font
					(size 1.27 1.27)
				)
			)
		)
		(duplicate_pad_numbers_are_jumpers no)
		(fp_line
			(start 0.7874 0.4064)
			(end -0.7874 0.4064)
			(stroke
				(width 0.1524)
				(type default)
			)
			(layer "F.SilkS")
		)
		(fp_line
			(start 0.7874 -0.4064)
			(end 0.7874 0.4064)
			(stroke
				(width 0.1524)
				(type default)
			)
			(layer "F.SilkS")
		)
		(fp_line
			(start -0.7874 0.4064)
			(end -0.7874 -0.4064)
			(stroke
				(width 0.1524)
				(type default)
			)
			(layer "F.SilkS")
		)
		(fp_line
			(start -0.7874 -0.4064)
			(end 0.7874 -0.4064)
			(stroke
				(width 0.1524)
				(type default)
			)
			(layer "F.SilkS")
		)
		(fp_poly
			(pts
				(xy -0.508 0.2794) (xy -0.508 0.2286) (xy -0.635 0.2286) (xy -0.635 -0.254) (xy -0.5334 -0.254)
				(xy -0.5334 -0.2794) (xy 0.5334 -0.2794) (xy 0.5334 -0.254) (xy 0.635 -0.254) (xy 0.635 0.254) (xy 0.5334 0.254)
				(xy 0.5334 0.2794)
			)
			(stroke
				(width 0)
				(type default)
			)
			(fill no)
			(layer "F.CrtYd")
		)
		(pad "1" smd rect
			(at 0.40005 0 180)
			(size 0.4572 0.508)
			(layers "F.Cu" "F.Mask" "F.Paste")
			(net "PV_VDDR_NODE1")
		)
		(pad "2" smd rect
			(at -0.40005 0 180)
			(size 0.4572 0.508)
			(layers "F.Cu" "F.Mask" "F.Paste")
			(net "PV_VDDR_NODE1_VREF_RW")
		)
	)
	(footprint ""
		(layer "F.Cu")
		(at 160.38322 -97.315528 180)
		(property "Reference" "R527"
			(at 4.331462 -0.623062 0)
			(unlocked yes)
			(layer "F.SilkS")
			(effects
				(font
					(size 0.7874 0.5842)
					(thickness 0.1524)
				)
				(justify left)
			)
		)
		(property "Value" ""
			(at 0 0 180)
			(layer "F.Fab")
			(effects
				(font
					(size 1.27 1.27)
				)
			)
		)
		(duplicate_pad_numbers_are_jumpers no)
		(fp_line
			(start 0.7874 0.4064)
			(end -0.7874 0.4064)
			(stroke
				(width 0.1524)
				(type default)
			)
			(layer "F.SilkS")
		)
		(fp_line
			(start 0.7874 -0.4064)
			(end 0.7874 0.4064)
			(stroke
				(width 0.1524)
				(type default)
			)
			(layer "F.SilkS")
		)
		(fp_line
			(start -0.7874 0.4064)
			(end -0.7874 -0.4064)
			(stroke
				(width 0.1524)
				(type default)
			)
			(layer "F.SilkS")
		)
		(fp_line
			(start -0.7874 -0.4064)
			(end 0.7874 -0.4064)
			(stroke
				(width 0.1524)
				(type default)
			)
			(layer "F.SilkS")
		)
		(fp_poly
			(pts
				(xy -0.508 0.2794) (xy -0.508 0.2286) (xy -0.635 0.2286) (xy -0.635 -0.254) (xy -0.5334 -0.254)
				(xy -0.5334 -0.2794) (xy 0.5334 -0.2794) (xy 0.5334 -0.254) (xy 0.635 -0.254) (xy 0.635 0.254) (xy 0.5334 0.254)
				(xy 0.5334 0.2794)
			)
			(stroke
				(width 0)
				(type default)
			)
			(fill no)
			(layer "F.CrtYd")
		)
		(pad "1" smd rect
			(at 0.40005 0 180)
			(size 0.4572 0.508)
			(layers "F.Cu" "F.Mask" "F.Paste")
			(net "P3V3_NODE1")
		)
		(pad "2" smd rect
			(at -0.40005 0 180)
			(size 0.4572 0.508)
			(layers "F.Cu" "F.Mask" "F.Paste")
			(net "FM_CPLD_NODE1_USB_PONRST_L")
		)
	)
	(footprint ""
		(layer "F.Cu")
		(at 154.551126 -167.785288 180)
		(property "Reference" "R573"
			(at 5.148834 4.164838 0)
			(unlocked yes)
			(layer "F.SilkS")
			(effects
				(font
					(size 0.7874 0.5842)
					(thickness 0.1524)
				)
				(justify left)
			)
		)
		(property "Value" ""
			(at 0 0 180)
			(layer "F.Fab")
			(effects
				(font
					(size 1.27 1.27)
				)
			)
		)
		(duplicate_pad_numbers_are_jumpers no)
		(fp_line
			(start 0.7874 0.4064)
			(end -0.7874 0.4064)
			(stroke
				(width 0.1524)
				(type default)
			)
			(layer "F.SilkS")
		)
		(fp_line
			(start 0.7874 -0.4064)
			(end 0.7874 0.4064)
			(stroke
				(width 0.1524)
				(type default)
			)
			(layer "F.SilkS")
		)
		(fp_line
			(start -0.7874 0.4064)
			(end -0.7874 -0.4064)
			(stroke
				(width 0.1524)
				(type default)
			)
			(layer "F.SilkS")
		)
		(fp_line
			(start -0.7874 -0.4064)
			(end 0.7874 -0.4064)
			(stroke
				(width 0.1524)
				(type default)
			)
			(layer "F.SilkS")
		)
		(fp_poly
			(pts
				(xy -0.508 0.2794) (xy -0.508 0.2286) (xy -0.635 0.2286) (xy -0.635 -0.254) (xy -0.5334 -0.254)
				(xy -0.5334 -0.2794) (xy 0.5334 -0.2794) (xy 0.5334 -0.254) (xy 0.635 -0.254) (xy 0.635 0.254) (xy 0.5334 0.254)
				(xy 0.5334 0.2794)
			)
			(stroke
				(width 0)
				(type default)
			)
			(fill no)
			(layer "F.CrtYd")
		)
		(pad "1" smd rect
			(at 0.40005 0 180)
			(size 0.4572 0.508)
			(layers "F.Cu" "F.Mask" "F.Paste")
			(net "SPI_LAN2_NVM_CS_N")
		)
		(pad "2" smd rect
			(at -0.40005 0 180)
			(size 0.4572 0.508)
			(layers "F.Cu" "F.Mask" "F.Paste")
			(net "LAN2_NVM_CS_N_R")
		)
	)
	(footprint ""
		(layer "F.Cu")
		(at 113.90376 -188.126624 -90)
		(property "Reference" "R997"
			(at -5.151882 -0.485902 90)
			(unlocked yes)
			(layer "F.SilkS")
			(effects
				(font
					(size 0.7874 0.5842)
					(thickness 0.1524)
				)
				(justify left)
			)
		)
		(property "Value" ""
			(at 0 0 270)
			(layer "F.Fab")
			(effects
				(font
					(size 1.27 1.27)
				)
			)
		)
		(duplicate_pad_numbers_are_jumpers no)
		(fp_line
			(start -0.7874 0.4064)
			(end -0.7874 -0.4064)
			(stroke
				(width 0.1524)
				(type default)
			)
			(layer "F.SilkS")
		)
		(fp_line
			(start 0.7874 0.4064)
			(end -0.7874 0.4064)
			(stroke
				(width 0.1524)
				(type default)
			)
			(layer "F.SilkS")
		)
		(fp_line
			(start -0.7874 -0.4064)
			(end 0.7874 -0.4064)
			(stroke
				(width 0.1524)
				(type default)
			)
			(layer "F.SilkS")
		)
		(fp_line
			(start 0.7874 -0.4064)
			(end 0.7874 0.4064)
			(stroke
				(width 0.1524)
				(type default)
			)
			(layer "F.SilkS")
		)
		(fp_poly
			(pts
				(xy -0.508 0.2794) (xy -0.508 0.2286) (xy -0.635 0.2286) (xy -0.635 -0.254) (xy -0.5334 -0.254)
				(xy -0.5334 -0.2794) (xy 0.5334 -0.2794) (xy 0.5334 -0.254) (xy 0.635 -0.254) (xy 0.635 0.254) (xy 0.5334 0.254)
				(xy 0.5334 0.2794)
			)
			(stroke
				(width 0)
				(type default)
			)
			(fill no)
			(layer "F.CrtYd")
		)
		(pad "1" smd rect
			(at 0.40005 0 270)
			(size 0.4572 0.508)
			(layers "F.Cu" "F.Mask" "F.Paste")
			(net "UART_T8_NODE4_RXD")
		)
		(pad "2" smd rect
			(at -0.40005 0 270)
			(size 0.4572 0.508)
			(layers "F.Cu" "F.Mask" "F.Paste")
			(net "UART_T8_NODE4_RXD_R")
		)
	)
	(footprint ""
		(layer "F.Cu")
		(at 163.154868 -80.60944 180)
		(property "Reference" "PC27"
			(at -3.537204 1.049274 0)
			(unlocked yes)
			(layer "F.SilkS")
			(effects
				(font
					(size 0.7874 0.5842)
					(thickness 0.1524)
				)
				(justify left)
			)
		)
		(property "Value" ""
			(at 0 0 180)
			(layer "F.Fab")
			(effects
				(font
					(size 1.27 1.27)
				)
			)
		)
		(duplicate_pad_numbers_are_jumpers no)
		(fp_line
			(start 1.905 0.8636)
			(end -1.905 0.8636)
			(stroke
				(width 0.1524)
				(type default)
			)
			(layer "F.SilkS")
		)
		(fp_line
			(start 1.905 -0.8636)
			(end 1.905 0.8636)
			(stroke
				(width 0.1524)
				(type default)
			)
			(layer "F.SilkS")
		)
		(fp_line
			(start 0 0.8382)
			(end 0 -0.8382)
			(stroke
				(width 0.1524)
				(type default)
			)
			(layer "F.SilkS")
		)
		(fp_line
			(start -1.905 0.8636)
			(end -1.905 -0.8636)
			(stroke
				(width 0.1524)
				(type default)
			)
			(layer "F.SilkS")
		)
		(fp_line
			(start -1.905 -0.8636)
			(end 1.905 -0.8636)
			(stroke
				(width 0.1524)
				(type default)
			)
			(layer "F.SilkS")
		)
		(fp_rect
			(start -1.524 0.7366)
			(end 1.524 -0.7366)
			(stroke
				(width 0)
				(type default)
			)
			(fill no)
			(layer "F.CrtYd")
		)
		(pad "1" smd rect
			(at 0.94996 0 180)
			(size 1.1176 1.3716)
			(layers "F.Cu" "F.Mask" "F.Paste")
			(net "P1V0_NODE1")
		)
		(pad "2" smd rect
			(at -0.94996 0 180)
			(size 1.1176 1.3716)
			(layers "F.Cu" "F.Mask" "F.Paste")
			(net "GND")
		)
	)
)
